#ISCELL
  mstr_misc dns *
  *
#ISCELL
  mstr_symbols cad_note *
  *
#ISCELL
  mstr_symbols design_note *
  *
#ISCELL
  mstr_symbols intel_corp_bpage *
  *
#CELL
  mstr_discrete res *
  page247_i1
#CELL
  mstr_discrete res *
  page247_i10
#CELL
  mstr_discrete res *
  page247_i11
#ISCELL
  mstr_symbols p3v3_stby *
  page247_i12
#ISCELL
  mstr_symbols gnd *
  page247_i13
#ISCELL
  mstr_symbols gnd *
  page247_i17
#CELL
  mstr_discrete cap *
  page247_i18
#ISCELL
  mstr_symbols p3v3_stby *
  page247_i19
#ISCELL
  mstr_symbols gnd *
  page247_i20
#ISCELL
  mstr_standard offpage *
  page247_i21
#ISCELL
  mstr_standard offpage *
  page247_i22
#ISCELL
  mstr_standard offpage *
  page247_i23
#ISCELL
  mstr_standard offpage *
  page247_i24
#ISCELL
  mstr_standard offpage *
  page247_i25
#ISCELL
  mstr_standard offpage *
  page247_i26
#ISCELL
  mstr_standard offpage *
  page247_i27
#ISCELL
  mstr_standard offpage *
  page247_i28
#ISCELL
  mstr_standard offpage *
  page247_i29
#CELL
  mstr_discrete res *
  page247_i3
#ISCELL
  mstr_standard offpage *
  page247_i30
#ISCELL
  mstr_symbols gnd *
  page247_i4
#CELL
  mstr_discrete res *
  page247_i5
#ISCELL
  mstr_symbols p3v3_stby *
  page247_i6
#CELL
  mstr_discrete res *
  page247_i67
#CELL
  mstr_discrete res *
  page247_i68
#ISCELL
  mstr_symbols gnd *
  page247_i7
#ISCELL
  mstr_standard offpage *
  page247_i70
#ISCELL
  mstr_standard offpage *
  page247_i72
#ISCELL
  mstr_symbols p3v3_stby *
  page247_i73
#ISCELL
  mstr_standard offpage *
  page247_i74
#ISCELL
  mstr_standard offpage *
  page247_i75
#CELL
  w_hdl pca9515adgkr-1-gp *
  page247_i77
#ISCELL
  mstr_symbols gnd *
  page247_i78
#ISCELL
  mstr_standard offpage *
  page247_i79
#CELL
  mstr_discrete res *
  page247_i8
#ISCELL
  mstr_standard offpage *
  page247_i80
#CELL
  mstr_discrete cap *
  page247_i81
#ISCELL
  mstr_symbols gnd *
  page247_i82
#ISCELL
  mstr_symbols p3v3_stby *
  page247_i83
#ISCELL
  mstr_standard offpage *
  page247_i84
#CELL
  dev_discrete cap_a *
  page247_i85
#ISCELL
  mstr_symbols gnd *
  page247_i86
#CELL
  mstr_discrete res *
  page247_i87
#ISCELL
  mstr_symbols p3v3_stby *
  page247_i88
#CELL
  mstr_memory at24c64 *
  page247_i89
#CELL
  mstr_discrete res *
  page247_i9
#CELL
  mstr_discrete res *
  page247_i90
#ISCELL
  mstr_symbols gnd *
  page247_i91
#CELL
  mstr_discrete res *
  page247_i92
#ISCELL
  mstr_symbols gnd *
  page247_i93
#CELL
  mstr_discrete res *
  page247_i94
#ISCELL
  mstr_standard offpage *
  page247_i95
#ISCELL
  mstr_standard offpage *
  page247_i96
#CELL
  w_hdl pca9555pwrg4-gp *
  page247_i97
